# S9S_MB_2U (Grand Teton) — schematic netlist excerpt (pin names and nets, part order shuffled) for the footprints in the layout excerpt that follows; sources: Cadence DE-HDL packaged netlist, KiCad conversion of 03242023_DA0F0TMBIJ0_F0T_Motherboard_J_brd_V01_OCP.brd

PR3851  Q_RES  10K 1% CHIP  pkg 0402LF  page 163 : A = P12V_OCP_FLTB_2 ; B = P3V3_AUX
R4608  Q_RES  33.2 1% CHIP  pkg 0402LF  page 214 : A = GPU_FPGA_RST_N ; B = GPU_FPGA_RST_R_N

(kicad_pcb
	(version 20260206)
	(generator "pcbnew")
	(generator_version "10.0")
	(general
		(thickness 1.6)
		(legacy_teardrops no)
	)
	(paper "A4")
	(title_block
		(title "03242023_DA0F0TMBIJ0_F0T_Motherboard_J_brd_V01_OCP.brd")
		(comment 1 "Grand Teton / footprints 329-330 of 6105")
	)
	(layers
		(0 "F.Cu" signal "TOP")
		(4 "In1.Cu" signal "GND")
		(6 "In2.Cu" signal "IN1")
		(8 "In3.Cu" signal "GND1")
		(10 "In4.Cu" signal "IN2")
		(12 "In5.Cu" signal "GND2")
		(14 "In6.Cu" signal "IN3")
		(16 "In7.Cu" signal "GND3")
		(18 "In8.Cu" signal "VCC")
		(20 "In9.Cu" signal "VCC1")
		(22 "In10.Cu" signal "GND4")
		(24 "In11.Cu" signal "IN4")
		(26 "In12.Cu" signal "GND5")
		(28 "In13.Cu" signal "IN5")
		(30 "In14.Cu" signal "GND6")
		(32 "In15.Cu" signal "IN6")
		(34 "In16.Cu" signal "GND7")
		(2 "B.Cu" signal "BOTTOM")
		(9 "F.Adhes" user "F.Adhesive")
		(11 "B.Adhes" user "B.Adhesive")
		(13 "F.Paste" user "Package Geometry/Pastemask Top")
		(15 "B.Paste" user "Package Geometry/Pastemask Bottom")
		(5 "F.SilkS" user "Ref Des/Silkscreen Top")
		(7 "B.SilkS" user "Ref Des/Silkscreen Bottom")
		(1 "F.Mask" user "Board Geometry/Soldermask Top")
		(3 "B.Mask" user "Board Geometry/Soldermask Bottom")
		(17 "Dwgs.User" user "User.Drawings")
		(19 "Cmts.User" user "User.Comments")
		(21 "Eco1.User" user "User.Eco1")
		(23 "Eco2.User" user "User.Eco2")
		(25 "Edge.Cuts" user "Board Geometry/Outline")
		(27 "Margin" user)
		(31 "F.CrtYd" user "Package Geometry/Place Bound Top")
		(29 "B.CrtYd" user "Package Geometry/Place Bound Bottom")
		(35 "F.Fab" user "Ref Des/Assembly Top")
		(33 "B.Fab" user "Ref Des/Assembly Bottom")
	)
	(footprint ""
		(layer "F.Cu")
		(at 200.6346 -122.748548)
		(property "Reference" "R4608"
			(at 0 0 0)
			(layer "F.SilkS")
			(hide yes)
			(effects
				(font
					(size 1.27 1.27)
				)
			)
		)
		(property "Value" ""
			(at 0 0 0)
			(layer "F.Fab")
			(effects
				(font
					(size 1.27 1.27)
				)
			)
		)
		(duplicate_pad_numbers_are_jumpers no)
		(fp_line
			(start -0.7874 -0.4064)
			(end 0.7874 -0.4064)
			(stroke
				(width 0.1524)
				(type default)
			)
			(layer "F.SilkS")
		)
		(fp_line
			(start -0.7874 0.4064)
			(end -0.7874 -0.4064)
			(stroke
				(width 0.1524)
				(type default)
			)
			(layer "F.SilkS")
		)
		(fp_line
			(start 0.7874 -0.4064)
			(end 0.7874 0.4064)
			(stroke
				(width 0.1524)
				(type default)
			)
			(layer "F.SilkS")
		)
		(fp_line
			(start 0.7874 0.4064)
			(end -0.7874 0.4064)
			(stroke
				(width 0.1524)
				(type default)
			)
			(layer "F.SilkS")
		)
		(fp_line
			(start -0.67945 -0.305054)
			(end -0.12065 -0.305054)
			(stroke
				(width 0.1)
				(type default)
			)
			(layer "F.Fab")
		)
		(fp_line
			(start -0.67945 0.3048)
			(end -0.67945 -0.305054)
			(stroke
				(width 0.1)
				(type default)
			)
			(layer "F.Fab")
		)
		(fp_line
			(start -0.12065 -0.305054)
			(end -0.12065 -0.2794)
			(stroke
				(width 0.1)
				(type default)
			)
			(layer "F.Fab")
		)
		(fp_line
			(start -0.12065 -0.2794)
			(end 0.12065 -0.2794)
			(stroke
				(width 0.1)
				(type default)
			)
			(layer "F.Fab")
		)
		(fp_line
			(start -0.12065 0.2794)
			(end -0.12065 0.3048)
			(stroke
				(width 0.1)
				(type default)
			)
			(layer "F.Fab")
		)
		(fp_line
			(start -0.12065 0.3048)
			(end -0.67945 0.3048)
			(stroke
				(width 0.1)
				(type default)
			)
			(layer "F.Fab")
		)
		(fp_line
			(start 0.120396 0.2794)
			(end -0.12065 0.2794)
			(stroke
				(width 0.1)
				(type default)
			)
			(layer "F.Fab")
		)
		(fp_line
			(start 0.120396 0.3048)
			(end 0.120396 0.2794)
			(stroke
				(width 0.1)
				(type default)
			)
			(layer "F.Fab")
		)
		(fp_line
			(start 0.12065 -0.3048)
			(end 0.67945 -0.3048)
			(stroke
				(width 0.1)
				(type default)
			)
			(layer "F.Fab")
		)
		(fp_line
			(start 0.12065 -0.2794)
			(end 0.12065 -0.3048)
			(stroke
				(width 0.1)
				(type default)
			)
			(layer "F.Fab")
		)
		(fp_line
			(start 0.67945 -0.3048)
			(end 0.67945 0.3048)
			(stroke
				(width 0.1)
				(type default)
			)
			(layer "F.Fab")
		)
		(fp_line
			(start 0.67945 0.3048)
			(end 0.120396 0.3048)
			(stroke
				(width 0.1)
				(type default)
			)
			(layer "F.Fab")
		)
		(pad "1" smd circle
			(at -0.40005 0)
			(size 0 0)
			(layers "F.Cu" "F.Mask" "F.Paste")
			(net "GPU_FPGA_RST_N")
		)
		(pad "2" smd circle
			(at 0.40005 0)
			(size 0 0)
			(layers "F.Cu" "F.Mask" "F.Paste")
			(net "GPU_FPGA_RST_R_N")
		)
	)
	(footprint ""
		(layer "F.Cu")
		(at 63.194438 -29.398722 180)
		(property "Reference" "PR3851"
			(at 0 0 180)
			(layer "F.SilkS")
			(hide yes)
			(effects
				(font
					(size 1.27 1.27)
				)
			)
		)
		(property "Value" ""
			(at 0 0 180)
			(layer "F.Fab")
			(effects
				(font
					(size 1.27 1.27)
				)
			)
		)
		(duplicate_pad_numbers_are_jumpers no)
		(fp_line
			(start 0.7874 0.4064)
			(end -0.7874 0.4064)
			(stroke
				(width 0.1524)
				(type default)
			)
			(layer "F.SilkS")
		)
		(fp_line
			(start 0.7874 -0.4064)
			(end 0.7874 0.4064)
			(stroke
				(width 0.1524)
				(type default)
			)
			(layer "F.SilkS")
		)
		(fp_line
			(start -0.7874 0.4064)
			(end -0.7874 -0.4064)
			(stroke
				(width 0.1524)
				(type default)
			)
			(layer "F.SilkS")
		)
		(fp_line
			(start -0.7874 -0.4064)
			(end 0.7874 -0.4064)
			(stroke
				(width 0.1524)
				(type default)
			)
			(layer "F.SilkS")
		)
		(fp_line
			(start 0.67945 0.3048)
			(end 0.120396 0.3048)
			(stroke
				(width 0.1)
				(type default)
			)
			(layer "F.Fab")
		)
		(fp_line
			(start 0.67945 -0.3048)
			(end 0.67945 0.3048)
			(stroke
				(width 0.1)
				(type default)
			)
			(layer "F.Fab")
		)
		(fp_line
			(start 0.12065 -0.2794)
			(end 0.12065 -0.3048)
			(stroke
				(width 0.1)
				(type default)
			)
			(layer "F.Fab")
		)
		(fp_line
			(start 0.12065 -0.3048)
			(end 0.67945 -0.3048)
			(stroke
				(width 0.1)
				(type default)
			)
			(layer "F.Fab")
		)
		(fp_line
			(start 0.120396 0.3048)
			(end 0.120396 0.2794)
			(stroke
				(width 0.1)
				(type default)
			)
			(layer "F.Fab")
		)
		(fp_line
			(start 0.120396 0.2794)
			(end -0.12065 0.2794)
			(stroke
				(width 0.1)
				(type default)
			)
			(layer "F.Fab")
		)
		(fp_line
			(start -0.12065 0.3048)
			(end -0.67945 0.3048)
			(stroke
				(width 0.1)
				(type default)
			)
			(layer "F.Fab")
		)
		(fp_line
			(start -0.12065 0.2794)
			(end -0.12065 0.3048)
			(stroke
				(width 0.1)
				(type default)
			)
			(layer "F.Fab")
		)
		(fp_line
			(start -0.12065 -0.2794)
			(end 0.12065 -0.2794)
			(stroke
				(width 0.1)
				(type default)
			)
			(layer "F.Fab")
		)
		(fp_line
			(start -0.12065 -0.305054)
			(end -0.12065 -0.2794)
			(stroke
				(width 0.1)
				(type default)
			)
			(layer "F.Fab")
		)
		(fp_line
			(start -0.67945 0.3048)
			(end -0.67945 -0.305054)
			(stroke
				(width 0.1)
				(type default)
			)
			(layer "F.Fab")
		)
		(fp_line
			(start -0.67945 -0.305054)
			(end -0.12065 -0.305054)
			(stroke
				(width 0.1)
				(type default)
			)
			(layer "F.Fab")
		)
		(pad "1" smd circle
			(at -0.40005 0 180)
			(size 0 0)
			(layers "F.Cu" "F.Mask" "F.Paste")
			(net "P12V_OCP_FLTB_2")
		)
		(pad "2" smd circle
			(at 0.40005 0 180)
			(size 0 0)
			(layers "F.Cu" "F.Mask" "F.Paste")
			(net "P3V3_AUX")
		)
	)
)
